FILE_TYPE = MULTI_PHYS_TABLE;

PART 'CONN_HDR_1X3_M_S_SMT'
CLASS=IO

{========================================================================================}
:CLS_PN               = JEDEC_TYPE                  | ALT_SYMBOLS                   | DESCRIPTION                                                       | CPN_STATUS ;
{========================================================================================}
 'G200-10551-01'      = 'S_M_H_1X3_S_P100_V1'       | '(S_M_H_1X3_S_P100_V1)'       | 'CON,3P,1X3,PIN HEADER,V/T,2.54MM,SMT'                            | ''        
 'G200-10318-01'      = 'S_M_H_1X3_S_P100'          | '(S_M_H_1X3_S_P100)'          | 'CON,3P,1X3,2.54MM PITCH,5.84MATING,HER,VER,SMT'                  | ''        
 'G200-11304-01'      = 'S_M_H_1X3_S_P100_V2'       | '(S_M_H_1X3_S_P100_V2)'       | 'CON,3P,1X3,PIN HEADER,WITH CAP,V/T,2.54MM,SMT'                   | ''        
 'G200-12006-01'      = 'S_M_H_1X3_S_P100_V3'       | '(S_M_H_1X3_S_P100_V3)'       | 'CON,3P,1X3,PIN HEADER,CONTACT PIN 4.0 MM,V/T,2.54MM,SMT'         | ''        
 'G205-10020-01'      = 'S_M_H_3P_S_P058'           | '(S_M_H_3P_S_P058)'           | 'CON,RF,MINI-SMA,50OHM'                                           | ''        
 'A200-00091-AW'      = 'S_M_H_1X3_S_P100_V1_H1057' | '(S_M_H_1X3_S_P100_V1_H1057)' | 'CON,3P,1X3,PIN HEADER,V/T,2.54MM/26.6MM,SMT'                     | ''        
 'G200-12958-01'      = 'S_M_H_1X3_S_P100_H276'     | '(S_M_H_1X3_S_P100_H276)'     | 'CON,HEADER,3PIN,2.54MM PITCH,3.00 MM MATING,0.76UM GOLD/GXT,SMT' | ''        
 'G200-12979-01'      = 'S_M_H_1X3_S_P100_V1_H258'  | '(S_M_H_1X3_S_P100_V1_H258)'  | 'CON,3P,1X3,HEADER,V/T,2.54MM PITH,SMT'                           | ''        

END_PART

END.

